# BASEBOARD_FAB2 (Tioga Pass) — schematic netlist excerpt (pin names and nets, part order shuffled) for the footprints in the layout excerpt that follows; sources: Cadence DE-HDL packaged netlist, KiCad conversion of Wiwynn_Tioga_Pass_MB.brd

R6D1  RES  100.0 1% CHIP  pkg 0402  page 21 : A = A_CPU0_DEF_RCOMP2 ; B = GND
T1P30  TPAD-SE-2P-GP  pkg DISCRET-GA1  page 256 : \1\ = L14_40OHM_6INCH ; GND1 = GND

(kicad_pcb
	(version 20260206)
	(generator "pcbnew")
	(generator_version "10.0")
	(general
		(thickness 1.6)
		(legacy_teardrops no)
	)
	(paper "A4")
	(title_block
		(title "Wiwynn_Tioga_Pass_MB.brd")
		(comment 1 "Tioga Pass / footprints 803-804 of 4770")
	)
	(layers
		(0 "F.Cu" signal "TOP")
		(4 "In1.Cu" signal "L2GND")
		(6 "In2.Cu" signal "L3")
		(8 "In3.Cu" signal "L4GND")
		(10 "In4.Cu" signal "L5")
		(12 "In5.Cu" signal "L6GND")
		(14 "In6.Cu" signal "L7VCC")
		(16 "In7.Cu" signal "L8VCC")
		(18 "In8.Cu" signal "L9GND")
		(20 "In9.Cu" signal "L10")
		(22 "In10.Cu" signal "L11GND")
		(24 "In11.Cu" signal "L12")
		(26 "In12.Cu" signal "L13GND")
		(2 "B.Cu" signal "BOTTOM")
		(9 "F.Adhes" user "F.Adhesive")
		(11 "B.Adhes" user "B.Adhesive")
		(13 "F.Paste" user "Package Geometry/Pastemask Top")
		(15 "B.Paste" user "Package Geometry/Pastemask Bottom")
		(5 "F.SilkS" user "Ref Des/Silkscreen Top")
		(7 "B.SilkS" user "Ref Des/Silkscreen Bottom")
		(1 "F.Mask" user "Board Geometry/Soldermask Top")
		(3 "B.Mask" user "Board Geometry/Soldermask Bottom")
		(17 "Dwgs.User" user "User.Drawings")
		(19 "Cmts.User" user "User.Comments")
		(21 "Eco1.User" user "User.Eco1")
		(23 "Eco2.User" user "User.Eco2")
		(25 "Edge.Cuts" user "Board Geometry/Outline")
		(27 "Margin" user)
		(31 "F.CrtYd" user "Package Geometry/Place Bound Top")
		(29 "B.CrtYd" user "Package Geometry/Place Bound Bottom")
		(35 "F.Fab" user "Ref Des/Assembly Top")
		(33 "B.Fab" user "Ref Des/Assembly Bottom")
	)
	(footprint ""
		(layer "F.Cu")
		(at 277.15972 -83.86064)
		(property "Reference" "R6D1"
			(at 0 0 0)
			(layer "F.SilkS")
			(hide yes)
			(effects
				(font
					(size 1.27 1.27)
				)
			)
		)
		(property "Value" ""
			(at 0 0 0)
			(layer "F.Fab")
			(effects
				(font
					(size 1.27 1.27)
				)
			)
		)
		(duplicate_pad_numbers_are_jumpers no)
		(fp_poly
			(pts
				(xy -0.2794 -0.1016) (xy 0.2794 -0.1016) (xy 0.2794 0.9906) (xy -0.2794 0.9906)
			)
			(stroke
				(width 0)
				(type default)
			)
			(fill no)
			(layer "F.CrtYd")
		)
		(fp_line
			(start -0.2794 -0.1016)
			(end -0.2794 0.9906)
			(stroke
				(width 0.1)
				(type default)
			)
			(layer "F.Fab")
		)
		(fp_line
			(start -0.2794 0.9906)
			(end 0.2794 0.9906)
			(stroke
				(width 0.1)
				(type default)
			)
			(layer "F.Fab")
		)
		(fp_line
			(start 0.2794 -0.1016)
			(end -0.2794 -0.1016)
			(stroke
				(width 0.1)
				(type default)
			)
			(layer "F.Fab")
		)
		(fp_line
			(start 0.2794 0.9906)
			(end 0.2794 -0.1016)
			(stroke
				(width 0.1)
				(type default)
			)
			(layer "F.Fab")
		)
		(pad "1" smd rect
			(at 0 0)
			(size 0.508 0.508)
			(layers "F.Cu" "F.Mask" "F.Paste")
			(net "A_CPU0_DEF_RCOMP2")
		)
		(pad "2" smd rect
			(at 0 0.889)
			(size 0.508 0.508)
			(layers "F.Cu" "F.Mask" "F.Paste")
			(net "GND")
		)
		(zone
			(layer "F.Cu")
			(hatch none 0.5)
			(connect_pads
				(clearance 0)
			)
			(min_thickness 0.25)
			(keepout
				(tracks allowed)
				(vias not_allowed)
				(pads allowed)
				(copperpour not_allowed)
				(footprints allowed)
			)
			(placement
				(enabled no)
				(sheetname "")
			)
			(fill
				(thermal_gap 0.5)
				(thermal_bridge_width 0.5)
				(island_removal_mode 0)
			)
			(polygon
				(pts
					(xy 276.90572 -83.60664) (xy 277.41372 -83.60664) (xy 277.41372 -83.22564) (xy 276.90572 -83.22564)
				)
			)
		)
		(zone
			(layer "F.Cu")
			(hatch none 0.5)
			(connect_pads
				(clearance 0)
			)
			(min_thickness 0.25)
			(keepout
				(tracks not_allowed)
				(vias allowed)
				(pads allowed)
				(copperpour not_allowed)
				(footprints allowed)
			)
			(placement
				(enabled no)
				(sheetname "")
			)
			(fill
				(thermal_gap 0.5)
				(thermal_bridge_width 0.5)
				(island_removal_mode 0)
			)
			(polygon
				(pts
					(xy 276.90572 -83.22564) (xy 277.41372 -83.22564) (xy 277.41372 -83.60664) (xy 276.90572 -83.60664)
				)
			)
		)
	)
	(footprint ""
		(layer "F.Cu")
		(at 34.417 10.7315 -90)
		(property "Reference" "T1P30"
			(at 0 0 270)
			(layer "F.SilkS")
			(hide yes)
			(effects
				(font
					(size 1.27 1.27)
				)
			)
		)
		(property "Value" "*"
			(at 0 -3.44805 270)
			(unlocked yes)
			(layer "F.Fab")
			(hide yes)
			(effects
				(font
					(size 0.889 0.889)
					(thickness 0.1524)
				)
			)
		)
		(property "Device Type" "TPAD-SE-2P-GP_DISCRET-GA1-TPADA"
			(at 0 -4.97205 270)
			(unlocked yes)
			(layer "F.Fab")
			(hide yes)
			(effects
				(font
					(size 0.889 0.889)
					(thickness 0.1524)
				)
			)
		)
		(duplicate_pad_numbers_are_jumpers no)
		(fp_line
			(start -1.016 2.286)
			(end -1.016 -2.286)
			(stroke
				(width 0.1524)
				(type default)
			)
			(layer "F.SilkS")
		)
		(fp_line
			(start 1.016 2.286)
			(end -1.016 2.286)
			(stroke
				(width 0.1524)
				(type default)
			)
			(layer "F.SilkS")
		)
		(fp_line
			(start -1.016 -2.286)
			(end 1.016 -2.286)
			(stroke
				(width 0.1524)
				(type default)
			)
			(layer "F.SilkS")
		)
		(fp_line
			(start 1.016 -2.286)
			(end 1.016 2.286)
			(stroke
				(width 0.1524)
				(type default)
			)
			(layer "F.SilkS")
		)
		(fp_rect
			(start -1.27 2.54)
			(end 1.27 -2.54)
			(stroke
				(width 0)
				(type default)
			)
			(fill no)
			(layer "F.CrtYd")
		)
		(fp_rect
			(start -1.27 2.54)
			(end 1.27 -2.54)
			(stroke
				(width 0)
				(type default)
			)
			(fill no)
			(layer "F.Fab")
		)
		(pad "1" thru_hole circle
			(at 0 -1.27 270)
			(size 1.524 1.524)
			(drill 0.9144)
			(layers "*.Cu" "*.Mask")
			(remove_unused_layers no)
			(net "L14_40OHM_6INCH")
			(clearance -0.0508)
			(thermal_gap 0.127)
			(padstack
				(mode front_inner_back)
				(layer "Inner"
					(shape circle)
					(size 1.1684 1.1684)
					(clearance 0.127)
				)
				(layer "B.Cu"
					(shape circle)
					(size 1.524 1.524)
					(clearance -0.0508)
				)
			)
		)
		(pad "GND1" thru_hole rect
			(at 0 1.27 270)
			(size 1.524 1.524)
			(drill 0.9144)
			(layers "*.Cu" "*.Mask")
			(remove_unused_layers no)
			(net "GND")
			(clearance -0.0508)
			(thermal_gap 0.127)
			(padstack
				(mode front_inner_back)
				(layer "Inner"
					(shape circle)
					(size 1.1684 1.1684)
					(clearance 0.127)
				)
				(layer "B.Cu"
					(shape rect)
					(size 1.524 1.524)
					(clearance -0.0508)
				)
			)
		)
	)
)
